(kicad_pcb
	(version 20260206)
	(generator "pcbnew")
	(generator_version "10.0")
	(general
		(thickness 1.6)
		(legacy_teardrops no)
	)
	(paper "A4")
	(title_block
		(title "15969-1a.1015WZS0858.brd")
		(comment 1 "Tioga Pass / footprints 35-36 of 295")
	)
	(layers
		(0 "F.Cu" signal "TOP")
		(4 "In1.Cu" signal "L2GND")
		(6 "In2.Cu" signal "L3")
		(8 "In3.Cu" signal "L4")
		(10 "In4.Cu" signal "L5GND")
		(2 "B.Cu" signal "BOTTOM")
		(9 "F.Adhes" user "F.Adhesive")
		(11 "B.Adhes" user "B.Adhesive")
		(13 "F.Paste" user "Package Geometry/Pastemask Top")
		(15 "B.Paste" user "Package Geometry/Pastemask Bottom")
		(5 "F.SilkS" user "Ref Des/Silkscreen Top")
		(7 "B.SilkS" user "Ref Des/Silkscreen Bottom")
		(1 "F.Mask" user "Board Geometry/Soldermask Top")
		(3 "B.Mask" user "Board Geometry/Soldermask Bottom")
		(17 "Dwgs.User" user "User.Drawings")
		(19 "Cmts.User" user "User.Comments")
		(21 "Eco1.User" user "User.Eco1")
		(23 "Eco2.User" user "User.Eco2")
		(25 "Edge.Cuts" user "Board Geometry/Outline")
		(27 "Margin" user)
		(31 "F.CrtYd" user "Package Geometry/Place Bound Top")
		(29 "B.CrtYd" user "Package Geometry/Place Bound Bottom")
		(35 "F.Fab" user "Ref Des/Assembly Top")
		(33 "B.Fab" user "Ref Des/Assembly Bottom")
	)
	(footprint ""
		(layer "F.Cu")
		(at 38.6969 0.8382 90)
		(property "Reference" "C19"
			(at 0 0 90)
			(layer "F.SilkS")
			(hide yes)
			(effects
				(font
					(size 1.27 1.27)
				)
			)
		)
		(property "Value" "SCD1U16V2KX-3GP"
			(at 1.1811 -2.7051 90)
			(unlocked yes)
			(layer "F.Fab")
			(hide yes)
			(effects
				(font
					(size 1.016 1.016)
					(thickness 0.1524)
				)
			)
		)
		(property "Device Type" "C402H22"
			(at 1.1811 -4.2291 90)
			(unlocked yes)
			(layer "F.Fab")
			(hide yes)
			(effects
				(font
					(size 1.016 1.016)
					(thickness 0.1524)
				)
			)
		)
		(duplicate_pad_numbers_are_jumpers no)
		(fp_rect
			(start -0.4318 0.9525)
			(end 0.4318 -0.9525)
			(stroke
				(width 0)
				(type default)
			)
			(fill no)
			(layer "F.CrtYd")
		)
		(fp_rect
			(start -0.4318 0.9525)
			(end 0.4318 -0.9525)
			(stroke
				(width 0)
				(type default)
			)
			(fill no)
			(layer "F.Fab")
		)
		(pad "1" smd custom
			(at 0 -0.4445 90)
			(size 0.1524 0.1524)
			(layers "F.Cu" "F.Mask" "F.Paste")
			(net "P3V3")
			(options
				(clearance outline)
				(anchor circle)
			)
			(primitives
				(gr_poly
					(pts
						(arc
							(start 0.3048 -0.2032)
							(mid 0.275042 -0.275042)
							(end 0.2032 -0.3048)
						)
						(arc
							(start -0.2032 -0.3048)
							(mid -0.275042 -0.275042)
							(end -0.3048 -0.2032)
						)
						(arc
							(start -0.3048 0.2032)
							(mid -0.275042 0.275042)
							(end -0.2032 0.3048)
						)
						(arc
							(start 0.2032 0.3048)
							(mid 0.275042 0.275042)
							(end 0.3048 0.2032)
						)
					)
					(width 0)
					(fill yes)
				)
			)
		)
		(pad "2" smd custom
			(at 0 0.4445 90)
			(size 0.1524 0.1524)
			(layers "F.Cu" "F.Mask" "F.Paste")
			(net "GND")
			(options
				(clearance outline)
				(anchor circle)
			)
			(primitives
				(gr_poly
					(pts
						(arc
							(start 0.3048 -0.2032)
							(mid 0.275042 -0.275042)
							(end 0.2032 -0.3048)
						)
						(arc
							(start -0.2032 -0.3048)
							(mid -0.275042 -0.275042)
							(end -0.3048 -0.2032)
						)
						(arc
							(start -0.3048 0.2032)
							(mid -0.275042 0.275042)
							(end -0.2032 0.3048)
						)
						(arc
							(start 0.2032 0.3048)
							(mid 0.275042 0.275042)
							(end 0.3048 0.2032)
						)
					)
					(width 0)
					(fill yes)
				)
			)
		)
	)
	(footprint ""
		(layer "F.Cu")
		(at 119.5832 -9.144 -90)
		(property "Reference" "R135"
			(at 0 0 270)
			(layer "F.SilkS")
			(hide yes)
			(effects
				(font
					(size 1.27 1.27)
				)
			)
		)
		(property "Value" "10KR2F-2-GP"
			(at 0.064008 -3.993896 270)
			(unlocked yes)
			(layer "F.Fab")
			(hide yes)
			(effects
				(font
					(size 1.016 1.016)
					(thickness 0.1524)
				)
			)
		)
		(property "Device Type" "R402H16"
			(at 0.064008 -5.517896 270)
			(unlocked yes)
			(layer "F.Fab")
			(hide yes)
			(effects
				(font
					(size 1.016 1.016)
					(thickness 0.1524)
				)
			)
		)
		(duplicate_pad_numbers_are_jumpers no)
		(fp_line
			(start -0.508 -0.9398)
			(end -0.508 0.9398)
			(stroke
				(width 0.1524)
				(type default)
			)
			(layer "F.SilkS")
		)
		(fp_line
			(start 0.508 -0.9398)
			(end -0.508 -0.9398)
			(stroke
				(width 0.1524)
				(type default)
			)
			(layer "F.SilkS")
		)
		(fp_rect
			(start -0.508 0.9398)
			(end 0.508 -0.9398)
			(stroke
				(width 0)
				(type default)
			)
			(fill no)
			(layer "F.CrtYd")
		)
		(fp_rect
			(start -0.508 0.9398)
			(end 0.508 -0.9398)
			(stroke
				(width 0)
				(type default)
			)
			(fill no)
			(layer "F.Fab")
		)
		(pad "1" smd custom
			(at 0 -0.4445 270)
			(size 0.1397 0.1397)
			(layers "F.Cu" "F.Mask" "F.Paste")
			(net "GPIO_P_IO1_0")
			(options
				(clearance outline)
				(anchor circle)
			)
			(primitives
				(gr_poly
					(pts
						(arc
							(start -0.1778 -0.2794)
							(mid -0.249642 -0.249642)
							(end -0.2794 -0.1778)
						)
						(arc
							(start -0.2794 0.1778)
							(mid -0.249642 0.249642)
							(end -0.1778 0.2794)
						)
						(arc
							(start 0.1778 0.2794)
							(mid 0.249642 0.249642)
							(end 0.2794 0.1778)
						)
						(arc
							(start 0.2794 -0.1778)
							(mid 0.249642 -0.249642)
							(end 0.1778 -0.2794)
						)
					)
					(width 0)
					(fill yes)
				)
			)
		)
		(pad "2" smd custom
			(at 0 0.4445 270)
			(size 0.1397 0.1397)
			(layers "F.Cu" "F.Mask" "F.Paste")
			(net "GND")
			(options
				(clearance outline)
				(anchor circle)
			)
			(primitives
				(gr_poly
					(pts
						(arc
							(start -0.1778 -0.2794)
							(mid -0.249642 -0.249642)
							(end -0.2794 -0.1778)
						)
						(arc
							(start -0.2794 0.1778)
							(mid -0.249642 0.249642)
							(end -0.1778 0.2794)
						)
						(arc
							(start 0.1778 0.2794)
							(mid 0.249642 0.249642)
							(end 0.2794 0.1778)
						)
						(arc
							(start 0.2794 -0.1778)
							(mid 0.249642 -0.249642)
							(end 0.1778 -0.2794)
						)
					)
					(width 0)
					(fill yes)
				)
			)
		)
	)
)
